(kicad_pcb
	(version 20241229)
	(generator "pcbnew")
	(generator_version "9.0")
	(general
		(thickness 1.63)
		(legacy_teardrops no)
	)
	(paper "A4")
	(title_block
		(title "CM4 Baseboard")
		(date "2026-01-05")
		(rev "1.1.1")
		(company "Antmicro Ltd")
		(comment 1 "www.antmicro.com")
		(comment 9 "footprints 492-496 of 506")
	)
	(layers
		(0 "F.Cu" signal)
		(4 "In1.Cu" power)
		(6 "In2.Cu" power)
		(8 "In3.Cu" signal)
		(10 "In4.Cu" signal)
		(2 "B.Cu" signal)
		(9 "F.Adhes" user "F.Adhesive")
		(11 "B.Adhes" user "B.Adhesive")
		(13 "F.Paste" user)
		(15 "B.Paste" user)
		(5 "F.SilkS" user "F.Silkscreen")
		(7 "B.SilkS" user "B.Silkscreen")
		(1 "F.Mask" user)
		(3 "B.Mask" user)
		(17 "Dwgs.User" user "User.Drawings")
		(19 "Cmts.User" user "User.Comments")
		(21 "Eco1.User" user "User.Eco1")
		(23 "Eco2.User" user "User.Eco2")
		(25 "Edge.Cuts" user)
		(27 "Margin" user)
		(31 "F.CrtYd" user "F.Courtyard")
		(29 "B.CrtYd" user "B.Courtyard")
		(35 "F.Fab" user)
		(33 "B.Fab" user)
	)
	(footprint "antmicro-footprints:R_0402_1005Metric"
		(layer "B.Cu")
		(at 65.242962 178.1665)
		(descr "Resistor SMD 0402")
		(tags "resistor SMD 0402")
		(property "Reference" "R807"
			(at -1.492962 1.28 0)
			(layer "B.SilkS")
			(effects
				(font
					(size 0.7 0.7)
					(thickness 0.15)
				)
				(justify right bottom mirror)
			)
		)
		(property "Value" "R_2k2_0402"
			(at -1.011843 -1.772047 0)
			(layer "B.Fab")
			(effects
				(font
					(size 0.7 0.7)
					(thickness 0.15)
				)
				(justify right bottom mirror)
			)
		)
		(property "Datasheet" "https://www.bourns.com/docs/product-datasheets/cr.pdf"
			(at 0 0 0)
			(layer "B.Fab")
			(hide yes)
			(effects
				(font
					(size 1.27 1.27)
					(thickness 0.15)
				)
			)
		)
		(property "Description" "SMD Chip Resistor, 2.2 kohm, ± 1%, 62.5 mW, 0402 [1005 Metric], Thick Film, General Purpose"
			(at 0 0 0)
			(layer "B.Fab")
			(hide yes)
			(effects
				(font
					(size 1.27 1.27)
					(thickness 0.15)
				)
			)
		)
		(property "MPN" "CR0402-FX-2201GLF"
			(at 0 0 0)
			(unlocked yes)
			(layer "B.Fab")
			(hide yes)
			(effects
				(font
					(size 1 1)
					(thickness 0.15)
				)
				(justify mirror)
			)
		)
		(property "Manufacturer" "Bourns"
			(at 0 0 0)
			(unlocked yes)
			(layer "B.Fab")
			(hide yes)
			(effects
				(font
					(size 1 1)
					(thickness 0.15)
				)
				(justify mirror)
			)
		)
		(property "License" "Apache-2.0"
			(at 0 0 0)
			(unlocked yes)
			(layer "B.Fab")
			(hide yes)
			(effects
				(font
					(size 1 1)
					(thickness 0.15)
				)
				(justify mirror)
			)
		)
		(property "Author" "Antmicro"
			(at 0 0 0)
			(unlocked yes)
			(layer "B.Fab")
			(hide yes)
			(effects
				(font
					(size 1 1)
					(thickness 0.15)
				)
				(justify mirror)
			)
		)
		(property "Val" "2k2"
			(at 0 0 0)
			(unlocked yes)
			(layer "B.Fab")
			(hide yes)
			(effects
				(font
					(size 1 1)
					(thickness 0.15)
				)
				(justify mirror)
			)
		)
		(property "Tolerance" "1%"
			(at 0 0 0)
			(unlocked yes)
			(layer "B.Fab")
			(hide yes)
			(effects
				(font
					(size 1 1)
					(thickness 0.15)
				)
				(justify mirror)
			)
		)
		(sheetname "/Peripherals/")
		(sheetfile "peripherals.kicad_sch")
		(attr smd)
		(fp_rect
			(start -0.925 0.47)
			(end 0.925 -0.47)
			(stroke
				(width 0.05)
				(type default)
			)
			(fill no)
			(layer "B.CrtYd")
		)
		(fp_rect
			(start -0.5 0.25)
			(end 0.5 -0.25)
			(stroke
				(width 0.15)
				(type solid)
			)
			(fill no)
			(layer "B.Fab")
		)
		(fp_text user "${REFERENCE}"
			(at -0.95 -3.168 180)
			(layer "B.Fab")
			(effects
				(font
					(size 0.7 0.7)
					(thickness 0.15)
				)
				(justify left bottom mirror)
			)
		)
		(fp_text user "Author: Antmicro"
			(at -0.95 -4.169 180)
			(layer "B.Fab")
			(effects
				(font
					(size 0.7 0.7)
					(thickness 0.15)
				)
				(justify left bottom mirror)
			)
		)
		(fp_text user "License: Apache-2.0"
			(at -0.95 -5.169 180)
			(layer "B.Fab")
			(effects
				(font
					(size 0.7 0.7)
					(thickness 0.15)
				)
				(justify left bottom mirror)
			)
		)
		(pad "1" smd roundrect
			(at -0.48 0)
			(size 0.59 0.64)
			(layers "B.Cu" "B.Mask" "B.Paste")
			(roundrect_rratio 0.25)
			(net 109 "Net-(C816-Pad2)")
			(pintype "passive")
		)
		(pad "2" smd roundrect
			(at 0.48 0)
			(size 0.59 0.64)
			(layers "B.Cu" "B.Mask" "B.Paste")
			(roundrect_rratio 0.25)
			(net 102 "Net-(C812-Pad2)")
			(pintype "passive")
		)
	)
	(footprint "antmicro-footprints:C_0805_2012Metric"
		(layer "B.Cu")
		(at 54.842962 171.3165 -90)
		(descr "Capacitor SMD 0805")
		(tags "capacitor SMD 0805")
		(property "Reference" "C408"
			(at 1.76 -0.4 90)
			(layer "B.SilkS")
			(effects
				(font
					(size 0.7 0.7)
					(thickness 0.15)
				)
				(justify left bottom mirror)
			)
		)
		(property "Value" "C_22u_25V_0805"
			(at -2.055717 -1.963152 90)
			(layer "B.Fab")
			(effects
				(font
					(size 0.7 0.7)
					(thickness 0.15)
				)
				(justify left bottom mirror)
			)
		)
		(property "Datasheet" "https://product.samsungsem.com/mlcc/CL21A226MAYNNN.do"
			(at 0 0 270)
			(layer "B.Fab")
			(hide yes)
			(effects
				(font
					(size 1.27 1.27)
					(thickness 0.15)
				)
			)
		)
		(property "Manufacturer" "Samsung Electro-Mechanics"
			(at 0 0 270)
			(unlocked yes)
			(layer "B.Fab")
			(hide yes)
			(effects
				(font
					(size 1 1)
					(thickness 0.15)
				)
				(justify mirror)
			)
		)
		(property "MPN" "CL21A226MAYNNNE"
			(at 0 0 270)
			(unlocked yes)
			(layer "B.Fab")
			(hide yes)
			(effects
				(font
					(size 1 1)
					(thickness 0.15)
				)
				(justify mirror)
			)
		)
		(property "Val" "22u"
			(at 0 0 270)
			(unlocked yes)
			(layer "B.Fab")
			(hide yes)
			(effects
				(font
					(size 1 1)
					(thickness 0.15)
				)
				(justify mirror)
			)
		)
		(property "License" "Apache-2.0"
			(at 0 0 270)
			(unlocked yes)
			(layer "B.Fab")
			(hide yes)
			(effects
				(font
					(size 1 1)
					(thickness 0.15)
				)
				(justify mirror)
			)
		)
		(property "Author" "Antmicro"
			(at 0 0 270)
			(unlocked yes)
			(layer "B.Fab")
			(hide yes)
			(effects
				(font
					(size 1 1)
					(thickness 0.15)
				)
				(justify mirror)
			)
		)
		(property "Voltage" "25V"
			(at 0 0 270)
			(unlocked yes)
			(layer "B.Fab")
			(hide yes)
			(effects
				(font
					(size 1 1)
					(thickness 0.15)
				)
				(justify mirror)
			)
		)
		(property "Dielectric" "X5R"
			(at 0 0 270)
			(unlocked yes)
			(layer "B.Fab")
			(hide yes)
			(effects
				(font
					(size 1 1)
					(thickness 0.15)
				)
				(justify mirror)
			)
		)
		(property "Public" "False"
			(at 0 0 270)
			(unlocked yes)
			(layer "B.Fab")
			(hide yes)
			(effects
				(font
					(size 1 1)
					(thickness 0.15)
				)
				(justify mirror)
			)
		)
		(sheetname "/Ethernet/")
		(sheetfile "ethernet.kicad_sch")
		(attr smd)
		(fp_line
			(start -0.3 0.7)
			(end 0.3 0.7)
			(stroke
				(width 0.15)
				(type solid)
			)
			(layer "B.SilkS")
		)
		(fp_line
			(start -0.3 -0.7)
			(end 0.3 -0.7)
			(stroke
				(width 0.15)
				(type solid)
			)
			(layer "B.SilkS")
		)
		(fp_rect
			(start 1.95 0.9)
			(end -1.95 -0.9)
			(stroke
				(width 0.05)
				(type default)
			)
			(fill no)
			(layer "B.CrtYd")
		)
		(fp_rect
			(start -0.95 0.675)
			(end 0.95 -0.675)
			(stroke
				(width 0.15)
				(type solid)
			)
			(fill no)
			(layer "B.Fab")
		)
		(fp_text user "${REFERENCE}"
			(at -1.9 -3.947 90)
			(layer "B.Fab")
			(effects
				(font
					(size 0.7 0.7)
					(thickness 0.15)
				)
				(justify left bottom mirror)
			)
		)
		(fp_text user "License: Apache-2.0"
			(at -1.9 -4.947 90)
			(layer "B.Fab")
			(effects
				(font
					(size 0.7 0.7)
					(thickness 0.15)
				)
				(justify left bottom mirror)
			)
		)
		(fp_text user "Author: Antmicro"
			(at -1.9 -5.947 90)
			(layer "B.Fab")
			(effects
				(font
					(size 0.7 0.7)
					(thickness 0.15)
				)
				(justify left bottom mirror)
			)
		)
		(pad "1" smd roundrect
			(at -1.1 0 270)
			(size 1.2 1.3)
			(layers "B.Cu" "B.Mask" "B.Paste")
			(roundrect_rratio 0.25)
			(net 47 "/Ethernet/POE_12V")
			(pintype "passive")
		)
		(pad "2" smd roundrect
			(at 1.1 0 270)
			(size 1.2 1.3)
			(layers "B.Cu" "B.Mask" "B.Paste")
			(roundrect_rratio 0.25)
			(net 3 "GND")
			(pintype "passive")
		)
	)
	(footprint "antmicro-footprints:TP_SMD_0.75mm"
		(layer "B.Cu")
		(at 80.65 146.9)
		(property "Reference" "TP203"
			(at 0.335 0.1 0)
			(layer "B.SilkS")
			(effects
				(font
					(size 0.7 0.7)
					(thickness 0.15)
				)
				(justify right bottom mirror)
			)
		)
		(property "Value" "TP_0.75mm_SMD"
			(at 0 -1.2 0)
			(layer "B.Fab")
			(effects
				(font
					(size 0.7 0.7)
					(thickness 0.15)
				)
				(justify right bottom mirror)
			)
		)
		(property "Author" "Antmicro"
			(at 0 0 0)
			(unlocked yes)
			(layer "B.Fab")
			(hide yes)
			(effects
				(font
					(size 1 1)
					(thickness 0.15)
				)
				(justify mirror)
			)
		)
		(property "License" "Apache-2.0"
			(at 0 0 0)
			(unlocked yes)
			(layer "B.Fab")
			(hide yes)
			(effects
				(font
					(size 1 1)
					(thickness 0.15)
				)
				(justify mirror)
			)
		)
		(property "MPN" ""
			(at 0 0 0)
			(unlocked yes)
			(layer "B.Fab")
			(hide yes)
			(effects
				(font
					(size 1 1)
					(thickness 0.15)
				)
				(justify mirror)
			)
		)
		(property "Manufacturer" ""
			(at 0 0 0)
			(unlocked yes)
			(layer "B.Fab")
			(hide yes)
			(effects
				(font
					(size 1 1)
					(thickness 0.15)
				)
				(justify mirror)
			)
		)
		(sheetname "/Compute module/")
		(sheetfile "compute-module.kicad_sch")
		(attr exclude_from_pos_files exclude_from_bom)
		(fp_circle
			(center 0 0)
			(end 0.475 0)
			(stroke
				(width 0.05)
				(type default)
			)
			(fill no)
			(layer "B.CrtYd")
		)
		(fp_text user "Author: Antmicro"
			(at -0.4 -3.901 180)
			(layer "B.Fab")
			(effects
				(font
					(size 0.7 0.7)
					(thickness 0.15)
				)
				(justify left bottom mirror)
			)
		)
		(fp_text user "License: Apache-2.0"
			(at -0.4 -5.101 180)
			(layer "B.Fab")
			(effects
				(font
					(size 0.7 0.7)
					(thickness 0.15)
				)
				(justify left bottom mirror)
			)
		)
		(fp_text user "${REFERENCE}"
			(at -0.4 -2.7 180)
			(layer "B.Fab")
			(effects
				(font
					(size 0.7 0.7)
					(thickness 0.15)
				)
				(justify left bottom mirror)
			)
		)
		(pad "1" smd circle
			(at 0 0)
			(size 0.75 0.75)
			(layers "B.Cu" "B.Mask")
			(net 213 "/Compute module/SYNC_IN")
			(pinfunction "1")
			(pintype "passive")
		)
	)
	(footprint "antmicro-footprints:R_0603_1608Metric"
		(layer "B.Cu")
		(at 47.217962 156.0165 90)
		(descr "Resistor SMD 0603")
		(tags "resistor SMD 0603")
		(property "Reference" "R308"
			(at 1.28 0.34 90)
			(layer "B.SilkS")
			(effects
				(font
					(size 0.7 0.7)
					(thickness 0.15)
				)
				(justify right bottom mirror)
			)
		)
		(property "Value" "R_0R_22.4A_0603"
			(at 0 -1.6 90)
			(layer "B.Fab")
			(effects
				(font
					(size 0.7 0.7)
					(thickness 0.15)
				)
				(justify right bottom mirror)
			)
		)
		(property "Datasheet" "https://fscdn.rohm.com/en/products/databook/datasheet/passive/resistor/chip_resistor/pmr-jpw-e.pdf"
			(at 0 0 90)
			(layer "B.Fab")
			(hide yes)
			(effects
				(font
					(size 1.27 1.27)
					(thickness 0.15)
				)
			)
		)
		(property "Manufacturer" "ROHM Semiconductor"
			(at 0 0 90)
			(unlocked yes)
			(layer "B.Fab")
			(hide yes)
			(effects
				(font
					(size 1 1)
					(thickness 0.15)
				)
				(justify mirror)
			)
		)
		(property "MPN" "PMR03EZPJ000"
			(at 0 0 90)
			(unlocked yes)
			(layer "B.Fab")
			(hide yes)
			(effects
				(font
					(size 1 1)
					(thickness 0.15)
				)
				(justify mirror)
			)
		)
		(property "Val" "0R"
			(at 0 0 90)
			(unlocked yes)
			(layer "B.Fab")
			(hide yes)
			(effects
				(font
					(size 1 1)
					(thickness 0.15)
				)
				(justify mirror)
			)
		)
		(property "Author" "Antmicro"
			(at 0 0 90)
			(unlocked yes)
			(layer "B.Fab")
			(hide yes)
			(effects
				(font
					(size 1 1)
					(thickness 0.15)
				)
				(justify mirror)
			)
		)
		(property "License" "Apache-2.0"
			(at 0 0 90)
			(unlocked yes)
			(layer "B.Fab")
			(hide yes)
			(effects
				(font
					(size 1 1)
					(thickness 0.15)
				)
				(justify mirror)
			)
		)
		(property "Max. Curr." "22.4A"
			(at 0 0 90)
			(unlocked yes)
			(layer "B.Fab")
			(hide yes)
			(effects
				(font
					(size 1 1)
					(thickness 0.15)
				)
				(justify mirror)
			)
		)
		(property "Tolerance" "template_tolerance"
			(at 0 0 90)
			(unlocked yes)
			(layer "B.Fab")
			(hide yes)
			(effects
				(font
					(size 1 1)
					(thickness 0.15)
				)
				(justify mirror)
			)
		)
		(sheetname "/Supply/")
		(sheetfile "supply.kicad_sch")
		(attr smd exclude_from_pos_files exclude_from_bom dnp)
		(fp_line
			(start -0.15 -0.4)
			(end 0.15 -0.4)
			(stroke
				(width 0.15)
				(type solid)
			)
			(layer "B.SilkS")
		)
		(fp_line
			(start -0.15 0.4)
			(end 0.15 0.4)
			(stroke
				(width 0.15)
				(type solid)
			)
			(layer "B.SilkS")
		)
		(fp_rect
			(start -1.25 0.65)
			(end 1.25 -0.65)
			(stroke
				(width 0.05)
				(type solid)
			)
			(fill no)
			(layer "B.CrtYd")
		)
		(fp_rect
			(start -0.8 0.4)
			(end 0.8 -0.4)
			(stroke
				(width 0.15)
				(type solid)
			)
			(fill no)
			(layer "B.Fab")
		)
		(fp_text user "Author: Antmicro"
			(at -1.25 -4.9 270)
			(layer "B.Fab")
			(effects
				(font
					(size 0.7 0.7)
					(thickness 0.15)
				)
				(justify left bottom mirror)
			)
		)
		(fp_text user "License: Apache-2.0"
			(at -1.25 -5.9 270)
			(layer "B.Fab")
			(effects
				(font
					(size 0.7 0.7)
					(thickness 0.15)
				)
				(justify left bottom mirror)
			)
		)
		(fp_text user "${REFERENCE}"
			(at -1.25 -3.898 270)
			(layer "B.Fab")
			(effects
				(font
					(size 0.7 0.7)
					(thickness 0.15)
				)
				(justify left bottom mirror)
			)
		)
		(pad "1" smd roundrect
			(at -0.7 0 90)
			(size 0.8 1)
			(layers "B.Cu" "B.Mask" "B.Paste")
			(roundrect_rratio 0.2)
			(net 21 "/Supply/VCC_IN")
			(pintype "passive")
		)
		(pad "2" smd roundrect
			(at 0.7 0 90)
			(size 0.8 1)
			(layers "B.Cu" "B.Mask" "B.Paste")
			(roundrect_rratio 0.2)
			(net 43 "VCC")
			(pintype "passive")
		)
	)
	(footprint "antmicro-footprints:C_0402_1005Metric"
		(layer "B.Cu")
		(at 54.742962 158.4165)
		(descr "Capacitor SMD 0402")
		(tags "capacitor SMD 0402")
		(property "Reference" "C311"
			(at -1.425 1.95 0)
			(layer "B.SilkS")
			(effects
				(font
					(size 0.7 0.7)
					(thickness 0.15)
				)
				(justify right bottom mirror)
			)
		)
		(property "Value" "C_1u_0402"
			(at -1.022927 -2.155213 0)
			(layer "B.Fab")
			(effects
				(font
					(size 0.7 0.7)
					(thickness 0.15)
				)
				(justify right bottom mirror)
			)
		)
		(property "Datasheet" "https://product.tdk.com/en/search/capacitor/ceramic/mlcc/info?part_no=C1005X6S1A105K050BC"
			(at 0 0 0)
			(layer "B.Fab")
			(hide yes)
			(effects
				(font
					(size 1.27 1.27)
					(thickness 0.15)
				)
			)
		)
		(property "Manufacturer" "TDK"
			(at 0 0 0)
			(unlocked yes)
			(layer "B.Fab")
			(hide yes)
			(effects
				(font
					(size 1 1)
					(thickness 0.15)
				)
				(justify mirror)
			)
		)
		(property "MPN" "C1005X6S1A105K050BC"
			(at 0 0 0)
			(unlocked yes)
			(layer "B.Fab")
			(hide yes)
			(effects
				(font
					(size 1 1)
					(thickness 0.15)
				)
				(justify mirror)
			)
		)
		(property "Val" "1u"
			(at 0 0 0)
			(unlocked yes)
			(layer "B.Fab")
			(hide yes)
			(effects
				(font
					(size 1 1)
					(thickness 0.15)
				)
				(justify mirror)
			)
		)
		(property "License" "Apache-2.0"
			(at 0 0 0)
			(unlocked yes)
			(layer "B.Fab")
			(hide yes)
			(effects
				(font
					(size 1 1)
					(thickness 0.15)
				)
				(justify mirror)
			)
		)
		(property "Author" "Antmicro"
			(at 0 0 0)
			(unlocked yes)
			(layer "B.Fab")
			(hide yes)
			(effects
				(font
					(size 1 1)
					(thickness 0.15)
				)
				(justify mirror)
			)
		)
		(property "Voltage" ""
			(at 0 0 0)
			(unlocked yes)
			(layer "B.Fab")
			(hide yes)
			(effects
				(font
					(size 1 1)
					(thickness 0.15)
				)
				(justify mirror)
			)
		)
		(property "Dielectric" ""
			(at 0 0 0)
			(unlocked yes)
			(layer "B.Fab")
			(hide yes)
			(effects
				(font
					(size 1 1)
					(thickness 0.15)
				)
				(justify mirror)
			)
		)
		(sheetname "/Supply/")
		(sheetfile "supply.kicad_sch")
		(attr smd)
		(fp_rect
			(start -0.925 0.47)
			(end 0.925 -0.47)
			(stroke
				(width 0.05)
				(type default)
			)
			(fill no)
			(layer "B.CrtYd")
		)
		(fp_line
			(start -0.494 -0.248)
			(end -0.494 0.25)
			(stroke
				(width 0.15)
				(type solid)
			)
			(layer "B.Fab")
		)
		(fp_line
			(start -0.494 0.25)
			(end 0.504 0.25)
			(stroke
				(width 0.15)
				(type solid)
			)
			(layer "B.Fab")
		)
		(fp_line
			(start 0.504 -0.248)
			(end -0.494 -0.248)
			(stroke
				(width 0.15)
				(type solid)
			)
			(layer "B.Fab")
		)
		(fp_line
			(start 0.504 0.25)
			(end 0.504 -0.248)
			(stroke
				(width 0.15)
				(type solid)
			)
			(layer "B.Fab")
		)
		(fp_text user "Author: Antmicro"
			(at -0.939 -3.399 180)
			(layer "B.Fab")
			(effects
				(font
					(size 0.7 0.7)
					(thickness 0.15)
				)
				(justify left bottom mirror)
			)
		)
		(fp_text user "License: Apache-2.0"
			(at -0.939 -5.799 180)
			(layer "B.Fab")
			(effects
				(font
					(size 0.7 0.7)
					(thickness 0.15)
				)
				(justify left bottom mirror)
			)
		)
		(fp_text user "${REFERENCE}"
			(at -0.939 -4.599 180)
			(layer "B.Fab")
			(effects
				(font
					(size 0.7 0.7)
					(thickness 0.15)
				)
				(justify left bottom mirror)
			)
		)
		(pad "1" smd roundrect
			(at -0.48 0)
			(size 0.59 0.64)
			(layers "B.Cu" "B.Mask" "B.Paste")
			(roundrect_rratio 0.25)
			(net 3 "GND")
			(pintype "passive")
		)
		(pad "2" smd roundrect
			(at 0.48 0)
			(size 0.59 0.64)
			(layers "B.Cu" "B.Mask" "B.Paste")
			(roundrect_rratio 0.25)
			(net 66 "/Supply/VCC_5V")
			(pintype "passive")
		)
	)
)
